FILE_TYPE = CONNECTIVITY;
{Allegro Design Entry HDL 17.2-2016 S081 (4005846) 1/11/2022}
"PAGE_NUMBER" = 72;
0"NC";
1"GND\g";
2"GND\g";
3"GND\g";
4"GND\g";
5"GND\g";
6"GND\g";
%"UNIVERSAL_GND"
"1","(-2800,-750)","0","logical_power","I1";
;
CDS_LIB"logical_power"
HDL_POWER"GND";
"A"6;
%"SOCKET4677_AZIF0045P001C01CS"
"37","(-1350,1775)","0","pure_quanta","I2";
;
PART_NUMBER"DGA^7000023"
PART_TYPE"SMLF"
MATERIAL"IO"
VALUE"SOCKET4677_AZIF0045-P001C01CS"
$LOCATION"U1"
CDS_LIB"pure_quanta"
NEEDS_NO_SIZE"TRUE"
CDS_LMAN_SYM_OUTLINE"-1050,2150,1050,-2100"
CDS_LOCATION"U1"
$SEC"37"
CDS_SEC"37";
"VSS0"
$PN"BR5"6;
"VSS356"
$PN"AW21"5;
"VSS357"
$PN"AW23"5;
"VSS358"
$PN"AW25"5;
"VSS360"
$PN"AW62"5;
"VSS361"
$PN"AW66"5;
"VSS362"
$PN"AW68"5;
"VSS363"
$PN"AW72"5;
"VSS364"
$PN"AW80"5;
"VSS365"
$PN"AW82"5;
"VSS366"
$PN"AW84"5;
"VSS367"
$PN"AW88"5;
"VSS369"
$PN"AY12"5;
"VSS370"
$PN"AY16"5;
"VSS371"
$PN"AY4"5;
"VSS372"
$PN"AY71"5;
"VSS373"
$PN"AY77"5;
"VSS374"
$PN"AY79"5;
"VSS375"
$PN"AY8"5;
"VSS376"
$PN"AY81"5;
"VSS377"
$PN"AY83"5;
"VSS393"
$PN"BA17"5;
"VSS394"
$PN"BA60"5;
"VSS395"
$PN"BA64"5;
"VSS397"
$PN"BA74"5;
"VSS398"
$PN"BA84"5;
"VSS399"
$PN"BA88"5;
"VSS400"
$PN"BB10"5;
"VSS401"
$PN"BB12"5;
"VSS402"
$PN"BB16"5;
"VSS403"
$PN"BB20"5;
"VSS404"
$PN"BB22"5;
"VSS405"
$PN"BB24"5;
"VSS406"
$PN"BB26"5;
"VSS407"
$PN"BB4"5;
"VSS408"
$PN"BB63"5;
"VSS409"
$PN"BB69"5;
"VSS410"
$PN"BB71"5;
"VSS411"
$PN"BB77"5;
"VSS412"
$PN"BB79"5;
"VSS413"
$PN"BB8"5;
"VSS414"
$PN"BB83"5;
"VSS415"
$PN"BB87"5;
"VSS416"
$PN"BB91"5;
"VSS417"
$PN"BC1"5;
"VSS418"
$PN"BC13"5;
"VSS419"
$PN"BC17"5;
"VSS420"
$PN"BC5"5;
"VSS421"
$PN"BC62"5;
"VSS422"
$PN"BC66"5;
"VSS423"
$PN"BC72"5;
"VSS424"
$PN"BC76"5;
"VSS425"
$PN"BC78"5;
"VSS426"
$PN"BC84"5;
"VSS427"
$PN"BC86"5;
"VSS428"
$PN"BC88"5;
"VSS429"
$PN"BC9"5;
"VSS430"
$PN"BD12"5;
"VSS431"
$PN"BD16"5;
"VSS432"
$PN"BD20"5;
"VSS433"
$PN"BD4"5;
"VSS434"
$PN"BD8"5;
"VSS435"
$PN"BD81"5;
"VSS437"
$PN"BD85"5;
"VSS439"
$PN"BD89"5;
"VSS440"
$PN"BE64"5;
"VSS441"
$PN"BE66"5;
"VSS442"
$PN"BE68"5;
"VSS443"
$PN"BE74"5;
"VSS444"
$PN"BE76"5;
"VSS445"
$PN"BE78"5;
"VSS446"
$PN"BE84"5;
"VSS447"
$PN"BF12"5;
"VSS448"
$PN"BF16"5;
"VSS449"
$PN"BF20"5;
"VSS450"
$PN"BF4"5;
"VSS451"
$PN"BF61"5;
"VSS452"
$PN"BF63"5;
"VSS453"
$PN"BF73"5;
"VSS454"
$PN"BF75"5;
"VSS455"
$PN"BF79"6;
"VSS456"
$PN"BF8"5;
"VSS457"
$PN"BF83"6;
"VSS458"
$PN"BG1"6;
"VSS459"
$PN"BG13"6;
"VSS460"
$PN"BG17"6;
"VSS461"
$PN"BG21"6;
"VSS462"
$PN"BG23"6;
"VSS463"
$PN"BG25"6;
"VSS464"
$PN"BG5"6;
"VSS465"
$PN"BG70"6;
"VSS466"
$PN"BG9"6;
"VSS467"
$PN"BH12"6;
"VSS468"
$PN"BH16"6;
"VSS469"
$PN"BH20"6;
"VSS470"
$PN"BH4"6;
"VSS472"
$PN"BH67"6;
"VSS473"
$PN"BH73"6;
"VSS474"
$PN"BH77"6;
"VSS475"
$PN"BH8"6;
"VSS476"
$PN"BH81"6;
"VSS477"
$PN"BH83"6;
"VSS479"
$PN"BJ62"6;
"VSS480"
$PN"BJ68"6;
"VSS481"
$PN"BJ80"6;
"VSS482"
$PN"BJ82"6;
"VSS483"
$PN"BJ84"6;
"VSS484"
$PN"BJ86"6;
"VSS485"
$PN"BJ88"6;
"VSS486"
$PN"BJ90"6;
"VSS487"
$PN"BK12"6;
"VSS488"
$PN"BK16"6;
"VSS489"
$PN"BK20"6;
"VSS490"
$PN"BK4"6;
"VSS491"
$PN"BK65"6;
"VSS492"
$PN"BK71"6;
"VSS494"
$PN"BK75"6;
"VSS495"
$PN"BK79"6;
"VSS496"
$PN"BK8"6;
"VSS497"
$PN"BL1"6;
"VSS498"
$PN"BL13"6;
"VSS499"
$PN"BL17"6;
"VSS500"
$PN"BL5"6;
"VSS501"
$PN"BL68"6;
"VSS502"
$PN"BL70"6;
"VSS503"
$PN"BL72"6;
"VSS504"
$PN"BL78"6;
"VSS505"
$PN"BL9"6;
"VSS506"
$PN"BM12"6;
"VSS507"
$PN"BM16"6;
"VSS508"
$PN"BM20"6;
"VSS509"
$PN"BM22"6;
"VSS510"
$PN"BM24"6;
"VSS511"
$PN"BM26"6;
"VSS512"
$PN"BM4"6;
"VSS513"
$PN"BM61"6;
"VSS515"
$PN"BM73"6;
"VSS516"
$PN"BM77"6;
"VSS517"
$PN"BM8"6;
"VSS518"
$PN"BN31"6;
"VSS519"
$PN"BN62"6;
"VSS520"
$PN"BN70"6;
"VSS522"
$PN"BP12"6;
"VSS523"
$PN"BP16"6;
"VSS524"
$PN"BP2"6;
"VSS525"
$PN"BP20"6;
"VSS527"
$PN"BP4"6;
"VSS528"
$PN"BP63"6;
"VSS529"
$PN"BP71"6;
"VSS530"
$PN"BP73"6;
"VSS531"
$PN"BP75"6;
"VSS532"
$PN"BP77"6;
"VSS533"
$PN"BP8"6;
"VSS535"
$PN"BR13"6;
"VSS536"
$PN"BR17"6;
"VSS538"
$PN"BR27"6;
"VSS539"
$PN"BR29"6;
"VSS540"
$PN"BR31"6;
"VSS541"
$PN"BR33"6;
"VSS572"
$PN"BR9"6;
%"UNIVERSAL_GND"
"1","(100,-750)","0","logical_power","I3";
;
CDS_LIB"logical_power"
HDL_POWER"GND";
"A"5;
%"UNIVERSAL_GND"
"1","(250,-750)","0","logical_power","I4";
;
CDS_LIB"logical_power"
HDL_POWER"GND";
"A"4;
%"SOCKET4677_AZIF0045P001C01CS"
"38","(1700,1775)","0","pure_quanta","I5";
;
PART_NUMBER"DGA^7000023"
MATERIAL"IO"
VALUE"SOCKET4677_AZIF0045-P001C01CS"
PART_TYPE"SMLF"
$LOCATION"U1"
CDS_LIB"pure_quanta"
NEEDS_NO_SIZE"TRUE"
CDS_LMAN_SYM_OUTLINE"-1050,2150,1050,-2100"
CDS_LOCATION"U1"
$SEC"38"
CDS_SEC"38";
"VSS198"
$PN"AK12"3;
"VSS199"
$PN"AK16"3;
"VSS200"
$PN"AK18"3;
"VSS201"
$PN"AK24"3;
"VSS202"
$PN"AK30"3;
"VSS203"
$PN"AK36"3;
"VSS204"
$PN"AK4"3;
"VSS205"
$PN"AK42"3;
"VSS206"
$PN"AK49"3;
"VSS207"
$PN"AK55"3;
"VSS208"
$PN"AK61"3;
"VSS209"
$PN"AK67"3;
"VSS210"
$PN"AK73"3;
"VSS211"
$PN"AK79"3;
"VSS212"
$PN"AK8"3;
"VSS213"
$PN"AK81"3;
"VSS214"
$PN"AK83"3;
"VSS215"
$PN"AK87"3;
"VSS216"
$PN"AK91"3;
"VSS217"
$PN"AL1"3;
"VSS218"
$PN"AL13"3;
"VSS219"
$PN"AL17"3;
"VSS220"
$PN"AL5"3;
"VSS221"
$PN"AL52"3;
"VSS222"
$PN"AL80"3;
"VSS223"
$PN"AL82"3;
"VSS224"
$PN"AL84"3;
"VSS225"
$PN"AL88"3;
"VSS226"
$PN"AL9"3;
"VSS227"
$PN"AM12"3;
"VSS228"
$PN"AM16"3;
"VSS229"
$PN"AM18"3;
"VSS230"
$PN"AM20"3;
"VSS231"
$PN"AM22"3;
"VSS232"
$PN"AM24"3;
"VSS233"
$PN"AM26"3;
"VSS234"
$PN"AM28"3;
"VSS235"
$PN"AM30"3;
"VSS236"
$PN"AM32"3;
"VSS237"
$PN"AM34"3;
"VSS238"
$PN"AM36"3;
"VSS239"
$PN"AM38"3;
"VSS240"
$PN"AM4"3;
"VSS241"
$PN"AM40"3;
"VSS242"
$PN"AM42"3;
"VSS243"
$PN"AM44"3;
"VSS244"
$PN"AM47"3;
"VSS245"
$PN"AM49"3;
"VSS246"
$PN"AM51"3;
"VSS247"
$PN"AM53"3;
"VSS248"
$PN"AM55"3;
"VSS249"
$PN"AM57"3;
"VSS250"
$PN"AM59"3;
"VSS251"
$PN"AM61"3;
"VSS252"
$PN"AM63"3;
"VSS253"
$PN"AM65"3;
"VSS254"
$PN"AM67"3;
"VSS255"
$PN"AM69"3;
"VSS256"
$PN"AM71"3;
"VSS257"
$PN"AM73"3;
"VSS258"
$PN"AM75"3;
"VSS259"
$PN"AM77"3;
"VSS260"
$PN"AM8"3;
"VSS261"
$PN"AN52"3;
"VSS262"
$PN"AN84"3;
"VSS263"
$PN"AN88"3;
"VSS264"
$PN"AP12"3;
"VSS265"
$PN"AP16"3;
"VSS266"
$PN"AP18"3;
"VSS267"
$PN"AP24"3;
"VSS268"
$PN"AP30"3;
"VSS269"
$PN"AP36"3;
"VSS270"
$PN"AP4"3;
"VSS271"
$PN"AP42"3;
"VSS272"
$PN"AP49"3;
"VSS273"
$PN"AP55"3;
"VSS274"
$PN"AP61"3;
"VSS275"
$PN"AP67"3;
"VSS276"
$PN"AP73"3;
"VSS277"
$PN"AP79"4;
"VSS278"
$PN"AP8"3;
"VSS279"
$PN"AP83"4;
"VSS280"
$PN"AP87"4;
"VSS281"
$PN"AP91"4;
"VSS282"
$PN"AR1"4;
"VSS283"
$PN"AR13"4;
"VSS284"
$PN"AR19"4;
"VSS285"
$PN"AR23"4;
"VSS286"
$PN"AR25"4;
"VSS287"
$PN"AR29"4;
"VSS288"
$PN"AR31"4;
"VSS289"
$PN"AR35"4;
"VSS290"
$PN"AR37"4;
"VSS291"
$PN"AR41"4;
"VSS292"
$PN"AR43"4;
"VSS293"
$PN"AR48"4;
"VSS294"
$PN"AR5"4;
"VSS295"
$PN"AR50"4;
"VSS296"
$PN"AR54"4;
"VSS297"
$PN"AR56"4;
"VSS298"
$PN"AR60"4;
"VSS299"
$PN"AR62"4;
"VSS300"
$PN"AR66"4;
"VSS301"
$PN"AR68"4;
"VSS302"
$PN"AR72"4;
"VSS303"
$PN"AR74"4;
"VSS304"
$PN"AR78"4;
"VSS305"
$PN"AR82"4;
"VSS306"
$PN"AR84"4;
"VSS307"
$PN"AR88"4;
"VSS308"
$PN"AR9"4;
"VSS309"
$PN"AT12"4;
"VSS310"
$PN"AT16"4;
"VSS311"
$PN"AT20"4;
"VSS312"
$PN"AT22"4;
"VSS313"
$PN"AT26"4;
"VSS314"
$PN"AT28"4;
"VSS315"
$PN"AT32"4;
"VSS316"
$PN"AT34"4;
"VSS317"
$PN"AT38"4;
"VSS318"
$PN"AT4"4;
"VSS319"
$PN"AT40"4;
"VSS320"
$PN"AT44"4;
"VSS321"
$PN"AT51"4;
"VSS322"
$PN"AT53"4;
"VSS323"
$PN"AT57"4;
"VSS324"
$PN"AT59"4;
"VSS325"
$PN"AT63"4;
"VSS326"
$PN"AT65"4;
"VSS327"
$PN"AT69"4;
"VSS328"
$PN"AT71"4;
"VSS329"
$PN"AT75"4;
"VSS330"
$PN"AT77"4;
"VSS331"
$PN"AT79"4;
"VSS332"
$PN"AT8"4;
"VSS333"
$PN"AU27"4;
"VSS334"
$PN"AU31"4;
"VSS335"
$PN"AU37"4;
"VSS336"
$PN"AU39"4;
"VSS337"
$PN"AU41"4;
"VSS338"
$PN"AU45"4;
"VSS339"
$PN"AU48"4;
"VSS340"
$PN"AU70"4;
"VSS341"
$PN"AU72"4;
"VSS342"
$PN"AU74"4;
"VSS343"
$PN"AU76"4;
"VSS344"
$PN"AU80"4;
"VSS345"
$PN"AU84"4;
"VSS346"
$PN"AU88"4;
"VSS347"
$PN"AV12"4;
"VSS348"
$PN"AV16"4;
"VSS349"
$PN"AV4"4;
"VSS350"
$PN"AV77"4;
"VSS351"
$PN"AV8"4;
"VSS352"
$PN"AV87"4;
"VSS353"
$PN"AV91"4;
"VSS354"
$PN"AW1"4;
"VSS355"
$PN"AW13"4;
"VSS359"
$PN"AW5"4;
"VSS368"
$PN"AW9"4;
%"UNIVERSAL_GND"
"1","(3150,-750)","0","logical_power","I6";
;
CDS_LIB"logical_power"
HDL_POWER"GND";
"A"3;
%"UNIVERSAL_GND"
"1","(3275,-750)","0","logical_power","I7";
;
CDS_LIB"logical_power"
HDL_POWER"GND";
"A"2;
%"SOCKET4677_AZIF0045P001C01CS"
"39","(4725,1775)","0","pure_quanta","I8";
;
PART_NUMBER"DGA^7000023"
PART_TYPE"SMLF"
MATERIAL"IO"
VALUE"SOCKET4677_AZIF0045-P001C01CS"
$LOCATION"U1"
CDS_LIB"pure_quanta"
NEEDS_NO_SIZE"TRUE"
CDS_LMAN_SYM_OUTLINE"-1050,2150,1050,-2100"
CDS_LOCATION"U1"
$SEC"39"
CDS_SEC"39";
"VSS38"
$PN"AA82"1;
"VSS39"
$PN"AA84"1;
"VSS40"
$PN"AA88"1;
"VSS41"
$PN"AB12"1;
"VSS42"
$PN"AB16"1;
"VSS43"
$PN"AB20"1;
"VSS44"
$PN"AB22"1;
"VSS45"
$PN"AB26"1;
"VSS46"
$PN"AB28"1;
"VSS47"
$PN"AB32"1;
"VSS48"
$PN"AB34"1;
"VSS49"
$PN"AB38"1;
"VSS50"
$PN"AB4"1;
"VSS51"
$PN"AB40"1;
"VSS52"
$PN"AB44"1;
"VSS53"
$PN"AB47"1;
"VSS54"
$PN"AB51"1;
"VSS55"
$PN"AB53"1;
"VSS56"
$PN"AB57"1;
"VSS57"
$PN"AB59"1;
"VSS58"
$PN"AB63"1;
"VSS59"
$PN"AB65"1;
"VSS60"
$PN"AB69"1;
"VSS61"
$PN"AB71"1;
"VSS62"
$PN"AB75"1;
"VSS63"
$PN"AB77"1;
"VSS64"
$PN"AB79"1;
"VSS65"
$PN"AB8"1;
"VSS66"
$PN"AB81"1;
"VSS67"
$PN"AB83"1;
"VSS68"
$PN"AB87"1;
"VSS69"
$PN"AB91"1;
"VSS70"
$PN"AC1"1;
"VSS71"
$PN"AC13"1;
"VSS72"
$PN"AC21"1;
"VSS73"
$PN"AC27"1;
"VSS74"
$PN"AC33"1;
"VSS75"
$PN"AC39"1;
"VSS76"
$PN"AC45"1;
"VSS77"
$PN"AC5"1;
"VSS78"
$PN"AC52"1;
"VSS79"
$PN"AC58"1;
"VSS80"
$PN"AC64"1;
"VSS81"
$PN"AC70"1;
"VSS82"
$PN"AC76"1;
"VSS83"
$PN"AC84"1;
"VSS84"
$PN"AC88"1;
"VSS85"
$PN"AC9"1;
"VSS86"
$PN"AD12"1;
"VSS87"
$PN"AD16"1;
"VSS88"
$PN"AD4"1;
"VSS89"
$PN"AD42"1;
"VSS90"
$PN"AD79"1;
"VSS91"
$PN"AD8"1;
"VSS92"
$PN"AD83"1;
"VSS93"
$PN"AE17"1;
"VSS94"
$PN"AE19"1;
"VSS95"
$PN"AE21"1;
"VSS96"
$PN"AE23"1;
"VSS97"
$PN"AE25"1;
"VSS98"
$PN"AE27"1;
"VSS99"
$PN"AE29"1;
"VSS100"
$PN"AE31"1;
"VSS101"
$PN"AE33"1;
"VSS102"
$PN"AE35"1;
"VSS103"
$PN"AE37"1;
"VSS104"
$PN"AE39"1;
"VSS105"
$PN"AE41"1;
"VSS106"
$PN"AE43"1;
"VSS107"
$PN"AE45"1;
"VSS108"
$PN"AE48"1;
"VSS109"
$PN"AE50"1;
"VSS110"
$PN"AE52"1;
"VSS111"
$PN"AE54"1;
"VSS112"
$PN"AE56"1;
"VSS113"
$PN"AE58"1;
"VSS114"
$PN"AE60"1;
"VSS115"
$PN"AE62"1;
"VSS116"
$PN"AE64"1;
"VSS117"
$PN"AE66"1;
"VSS118"
$PN"AE68"2;
"VSS119"
$PN"AE70"2;
"VSS120"
$PN"AE72"2;
"VSS121"
$PN"AE74"2;
"VSS122"
$PN"AE76"2;
"VSS123"
$PN"AE78"2;
"VSS124"
$PN"AE84"2;
"VSS125"
$PN"AE88"2;
"VSS126"
$PN"AF12"2;
"VSS127"
$PN"AF16"2;
"VSS128"
$PN"AF4"2;
"VSS129"
$PN"AF42"2;
"VSS130"
$PN"AF8"2;
"VSS131"
$PN"AF81"2;
"VSS132"
$PN"AF87"2;
"VSS133"
$PN"AF91"2;
"VSS134"
$PN"AG1"2;
"VSS135"
$PN"AG13"2;
"VSS136"
$PN"AG21"2;
"VSS137"
$PN"AG27"2;
"VSS138"
$PN"AG33"2;
"VSS139"
$PN"AG39"2;
"VSS140"
$PN"AG45"2;
"VSS141"
$PN"AG5"2;
"VSS142"
$PN"AG52"2;
"VSS143"
$PN"AG58"2;
"VSS144"
$PN"AG64"2;
"VSS145"
$PN"AG70"2;
"VSS146"
$PN"AG76"2;
"VSS147"
$PN"AG84"2;
"VSS148"
$PN"AG88"2;
"VSS149"
$PN"AG9"2;
"VSS150"
$PN"AH12"2;
"VSS151"
$PN"AH16"2;
"VSS152"
$PN"AH20"2;
"VSS153"
$PN"AH22"2;
"VSS154"
$PN"AH26"2;
"VSS155"
$PN"AH28"2;
"VSS156"
$PN"AH32"2;
"VSS157"
$PN"AH34"2;
"VSS158"
$PN"AH38"2;
"VSS159"
$PN"AH4"2;
"VSS160"
$PN"AH40"2;
"VSS161"
$PN"AH44"2;
"VSS162"
$PN"AH47"2;
"VSS163"
$PN"AH51"2;
"VSS164"
$PN"AH53"2;
"VSS165"
$PN"AH57"2;
"VSS166"
$PN"AH59"2;
"VSS167"
$PN"AH63"2;
"VSS168"
$PN"AH65"2;
"VSS169"
$PN"AH69"2;
"VSS170"
$PN"AH71"2;
"VSS171"
$PN"AH75"2;
"VSS172"
$PN"AH77"2;
"VSS173"
$PN"AH79"2;
"VSS174"
$PN"AH8"2;
"VSS175"
$PN"AH83"2;
"VSS176"
$PN"AJ19"2;
"VSS177"
$PN"AJ23"2;
"VSS178"
$PN"AJ25"2;
"VSS179"
$PN"AJ29"2;
"VSS180"
$PN"AJ31"2;
"VSS181"
$PN"AJ35"2;
"VSS182"
$PN"AJ37"2;
"VSS183"
$PN"AJ41"2;
"VSS184"
$PN"AJ43"2;
"VSS185"
$PN"AJ48"2;
"VSS186"
$PN"AJ50"2;
"VSS187"
$PN"AJ54"2;
"VSS188"
$PN"AJ56"2;
"VSS189"
$PN"AJ60"2;
"VSS190"
$PN"AJ62"2;
"VSS191"
$PN"AJ66"2;
"VSS192"
$PN"AJ68"2;
"VSS193"
$PN"AJ72"2;
"VSS194"
$PN"AJ74"2;
"VSS195"
$PN"AJ78"2;
"VSS196"
$PN"AJ84"2;
"VSS197"
$PN"AJ88"2;
%"UNIVERSAL_GND"
"1","(6175,-750)","0","logical_power","I9";
;
CDS_LIB"logical_power"
HDL_POWER"GND";
"A"1;
END.
